(kicad_pcb
	(version 20260206)
	(generator "pcbnew")
	(generator_version "10.0")
	(general
		(thickness 1.6)
		(legacy_teardrops no)
	)
	(paper "A4")
	(title_block
		(title "03242023_DA0F0TMBIJ0_F0T_Motherboard_J_brd_V01_OCP.brd")
		(comment 1 "Grand Teton / footprints 4559-4564 of 6105")
	)
	(layers
		(0 "F.Cu" signal "TOP")
		(4 "In1.Cu" signal "GND")
		(6 "In2.Cu" signal "IN1")
		(8 "In3.Cu" signal "GND1")
		(10 "In4.Cu" signal "IN2")
		(12 "In5.Cu" signal "GND2")
		(14 "In6.Cu" signal "IN3")
		(16 "In7.Cu" signal "GND3")
		(18 "In8.Cu" signal "VCC")
		(20 "In9.Cu" signal "VCC1")
		(22 "In10.Cu" signal "GND4")
		(24 "In11.Cu" signal "IN4")
		(26 "In12.Cu" signal "GND5")
		(28 "In13.Cu" signal "IN5")
		(30 "In14.Cu" signal "GND6")
		(32 "In15.Cu" signal "IN6")
		(34 "In16.Cu" signal "GND7")
		(2 "B.Cu" signal "BOTTOM")
		(9 "F.Adhes" user "F.Adhesive")
		(11 "B.Adhes" user "B.Adhesive")
		(13 "F.Paste" user "Package Geometry/Pastemask Top")
		(15 "B.Paste" user "Package Geometry/Pastemask Bottom")
		(5 "F.SilkS" user "Ref Des/Silkscreen Top")
		(7 "B.SilkS" user "Ref Des/Silkscreen Bottom")
		(1 "F.Mask" user "Board Geometry/Soldermask Top")
		(3 "B.Mask" user "Board Geometry/Soldermask Bottom")
		(17 "Dwgs.User" user "User.Drawings")
		(19 "Cmts.User" user "User.Comments")
		(21 "Eco1.User" user "User.Eco1")
		(23 "Eco2.User" user "User.Eco2")
		(25 "Edge.Cuts" user "Board Geometry/Outline")
		(27 "Margin" user)
		(31 "F.CrtYd" user "Package Geometry/Place Bound Top")
		(29 "B.CrtYd" user "Package Geometry/Place Bound Bottom")
		(35 "F.Fab" user "Ref Des/Assembly Top")
		(33 "B.Fab" user "Ref Des/Assembly Bottom")
	)
	(footprint ""
		(layer "B.Cu")
		(at 154.4955 -190.87211 -90)
		(property "Reference" "R1244"
			(at 0 0 90)
			(layer "B.SilkS")
			(hide yes)
			(effects
				(font
					(size 1.27 1.27)
				)
				(justify mirror)
			)
		)
		(property "Value" ""
			(at 0 0 90)
			(layer "B.Fab")
			(effects
				(font
					(size 1.27 1.27)
				)
				(justify mirror)
			)
		)
		(duplicate_pad_numbers_are_jumpers no)
		(fp_line
			(start -0.7874 0.4064)
			(end 0.7874 0.4064)
			(stroke
				(width 0.1524)
				(type default)
			)
			(layer "B.SilkS")
		)
		(fp_line
			(start 0.7874 0.4064)
			(end 0.7874 -0.4064)
			(stroke
				(width 0.1524)
				(type default)
			)
			(layer "B.SilkS")
		)
		(fp_line
			(start -0.7874 -0.4064)
			(end -0.7874 0.4064)
			(stroke
				(width 0.1524)
				(type default)
			)
			(layer "B.SilkS")
		)
		(fp_line
			(start 0.7874 -0.4064)
			(end -0.7874 -0.4064)
			(stroke
				(width 0.1524)
				(type default)
			)
			(layer "B.SilkS")
		)
		(fp_line
			(start -0.67945 0.3048)
			(end -0.120396 0.3048)
			(stroke
				(width 0.1)
				(type default)
			)
			(layer "B.Fab")
		)
		(fp_line
			(start -0.120396 0.3048)
			(end -0.120396 0.2794)
			(stroke
				(width 0.1)
				(type default)
			)
			(layer "B.Fab")
		)
		(fp_line
			(start 0.12065 0.3048)
			(end 0.67945 0.3048)
			(stroke
				(width 0.1)
				(type default)
			)
			(layer "B.Fab")
		)
		(fp_line
			(start 0.67945 0.3048)
			(end 0.67945 -0.305054)
			(stroke
				(width 0.1)
				(type default)
			)
			(layer "B.Fab")
		)
		(fp_line
			(start -0.120396 0.2794)
			(end 0.12065 0.2794)
			(stroke
				(width 0.1)
				(type default)
			)
			(layer "B.Fab")
		)
		(fp_line
			(start 0.12065 0.2794)
			(end 0.12065 0.3048)
			(stroke
				(width 0.1)
				(type default)
			)
			(layer "B.Fab")
		)
		(fp_line
			(start -0.12065 -0.2794)
			(end -0.12065 -0.3048)
			(stroke
				(width 0.1)
				(type default)
			)
			(layer "B.Fab")
		)
		(fp_line
			(start 0.12065 -0.2794)
			(end -0.12065 -0.2794)
			(stroke
				(width 0.1)
				(type default)
			)
			(layer "B.Fab")
		)
		(fp_line
			(start -0.67945 -0.3048)
			(end -0.67945 0.3048)
			(stroke
				(width 0.1)
				(type default)
			)
			(layer "B.Fab")
		)
		(fp_line
			(start -0.12065 -0.3048)
			(end -0.67945 -0.3048)
			(stroke
				(width 0.1)
				(type default)
			)
			(layer "B.Fab")
		)
		(fp_line
			(start 0.12065 -0.305054)
			(end 0.12065 -0.2794)
			(stroke
				(width 0.1)
				(type default)
			)
			(layer "B.Fab")
		)
		(fp_line
			(start 0.67945 -0.305054)
			(end 0.12065 -0.305054)
			(stroke
				(width 0.1)
				(type default)
			)
			(layer "B.Fab")
		)
		(pad "1" smd circle
			(at 0.40005 0 90)
			(size 0 0)
			(layers "B.Cu" "B.Mask" "B.Paste")
			(net "PVNN_TERM_CPU1")
		)
		(pad "2" smd circle
			(at -0.40005 0 90)
			(size 0 0)
			(layers "B.Cu" "B.Mask" "B.Paste")
			(net "H_CPU_PM_FAST_WAKE_N")
		)
	)
	(footprint ""
		(layer "B.Cu")
		(at 404.09241 -194.87007 90)
		(property "Reference" "R1239"
			(at 0 0 90)
			(layer "B.SilkS")
			(hide yes)
			(effects
				(font
					(size 1.27 1.27)
				)
				(justify mirror)
			)
		)
		(property "Value" ""
			(at 0 0 90)
			(layer "B.Fab")
			(effects
				(font
					(size 1.27 1.27)
				)
				(justify mirror)
			)
		)
		(duplicate_pad_numbers_are_jumpers no)
		(fp_line
			(start 0.7874 -0.4064)
			(end -0.7874 -0.4064)
			(stroke
				(width 0.1524)
				(type default)
			)
			(layer "B.SilkS")
		)
		(fp_line
			(start -0.7874 -0.4064)
			(end -0.7874 0.4064)
			(stroke
				(width 0.1524)
				(type default)
			)
			(layer "B.SilkS")
		)
		(fp_line
			(start 0.7874 0.4064)
			(end 0.7874 -0.4064)
			(stroke
				(width 0.1524)
				(type default)
			)
			(layer "B.SilkS")
		)
		(fp_line
			(start -0.7874 0.4064)
			(end 0.7874 0.4064)
			(stroke
				(width 0.1524)
				(type default)
			)
			(layer "B.SilkS")
		)
		(fp_line
			(start 0.67945 -0.305054)
			(end 0.12065 -0.305054)
			(stroke
				(width 0.1)
				(type default)
			)
			(layer "B.Fab")
		)
		(fp_line
			(start 0.12065 -0.305054)
			(end 0.12065 -0.2794)
			(stroke
				(width 0.1)
				(type default)
			)
			(layer "B.Fab")
		)
		(fp_line
			(start -0.12065 -0.3048)
			(end -0.67945 -0.3048)
			(stroke
				(width 0.1)
				(type default)
			)
			(layer "B.Fab")
		)
		(fp_line
			(start -0.67945 -0.3048)
			(end -0.67945 0.3048)
			(stroke
				(width 0.1)
				(type default)
			)
			(layer "B.Fab")
		)
		(fp_line
			(start 0.12065 -0.2794)
			(end -0.12065 -0.2794)
			(stroke
				(width 0.1)
				(type default)
			)
			(layer "B.Fab")
		)
		(fp_line
			(start -0.12065 -0.2794)
			(end -0.12065 -0.3048)
			(stroke
				(width 0.1)
				(type default)
			)
			(layer "B.Fab")
		)
		(fp_line
			(start 0.12065 0.2794)
			(end 0.12065 0.3048)
			(stroke
				(width 0.1)
				(type default)
			)
			(layer "B.Fab")
		)
		(fp_line
			(start -0.120396 0.2794)
			(end 0.12065 0.2794)
			(stroke
				(width 0.1)
				(type default)
			)
			(layer "B.Fab")
		)
		(fp_line
			(start 0.67945 0.3048)
			(end 0.67945 -0.305054)
			(stroke
				(width 0.1)
				(type default)
			)
			(layer "B.Fab")
		)
		(fp_line
			(start 0.12065 0.3048)
			(end 0.67945 0.3048)
			(stroke
				(width 0.1)
				(type default)
			)
			(layer "B.Fab")
		)
		(fp_line
			(start -0.120396 0.3048)
			(end -0.120396 0.2794)
			(stroke
				(width 0.1)
				(type default)
			)
			(layer "B.Fab")
		)
		(fp_line
			(start -0.67945 0.3048)
			(end -0.120396 0.3048)
			(stroke
				(width 0.1)
				(type default)
			)
			(layer "B.Fab")
		)
		(pad "1" smd circle
			(at 0.40005 0 270)
			(size 0 0)
			(layers "B.Cu" "B.Mask" "B.Paste")
			(net "GND")
		)
		(pad "2" smd circle
			(at -0.40005 0 270)
			(size 0 0)
			(layers "B.Cu" "B.Mask" "B.Paste")
			(net "PUD_XTAL_CPU0_MODE1")
		)
	)
	(footprint ""
		(layer "B.Cu")
		(at 183.7436 -21.351748 -90)
		(property "Reference" "R1319"
			(at 0 0 90)
			(layer "B.SilkS")
			(hide yes)
			(effects
				(font
					(size 1.27 1.27)
				)
				(justify mirror)
			)
		)
		(property "Value" ""
			(at 0 0 90)
			(layer "B.Fab")
			(effects
				(font
					(size 1.27 1.27)
				)
				(justify mirror)
			)
		)
		(duplicate_pad_numbers_are_jumpers no)
		(fp_line
			(start -0.7874 0.4064)
			(end 0.7874 0.4064)
			(stroke
				(width 0.1524)
				(type default)
			)
			(layer "B.SilkS")
		)
		(fp_line
			(start 0.7874 0.4064)
			(end 0.7874 -0.4064)
			(stroke
				(width 0.1524)
				(type default)
			)
			(layer "B.SilkS")
		)
		(fp_line
			(start -0.7874 -0.4064)
			(end -0.7874 0.4064)
			(stroke
				(width 0.1524)
				(type default)
			)
			(layer "B.SilkS")
		)
		(fp_line
			(start 0.7874 -0.4064)
			(end -0.7874 -0.4064)
			(stroke
				(width 0.1524)
				(type default)
			)
			(layer "B.SilkS")
		)
		(fp_line
			(start -0.67945 0.3048)
			(end -0.120396 0.3048)
			(stroke
				(width 0.1)
				(type default)
			)
			(layer "B.Fab")
		)
		(fp_line
			(start -0.120396 0.3048)
			(end -0.120396 0.2794)
			(stroke
				(width 0.1)
				(type default)
			)
			(layer "B.Fab")
		)
		(fp_line
			(start 0.12065 0.3048)
			(end 0.67945 0.3048)
			(stroke
				(width 0.1)
				(type default)
			)
			(layer "B.Fab")
		)
		(fp_line
			(start 0.67945 0.3048)
			(end 0.67945 -0.305054)
			(stroke
				(width 0.1)
				(type default)
			)
			(layer "B.Fab")
		)
		(fp_line
			(start -0.120396 0.2794)
			(end 0.12065 0.2794)
			(stroke
				(width 0.1)
				(type default)
			)
			(layer "B.Fab")
		)
		(fp_line
			(start 0.12065 0.2794)
			(end 0.12065 0.3048)
			(stroke
				(width 0.1)
				(type default)
			)
			(layer "B.Fab")
		)
		(fp_line
			(start -0.12065 -0.2794)
			(end -0.12065 -0.3048)
			(stroke
				(width 0.1)
				(type default)
			)
			(layer "B.Fab")
		)
		(fp_line
			(start 0.12065 -0.2794)
			(end -0.12065 -0.2794)
			(stroke
				(width 0.1)
				(type default)
			)
			(layer "B.Fab")
		)
		(fp_line
			(start -0.67945 -0.3048)
			(end -0.67945 0.3048)
			(stroke
				(width 0.1)
				(type default)
			)
			(layer "B.Fab")
		)
		(fp_line
			(start -0.12065 -0.3048)
			(end -0.67945 -0.3048)
			(stroke
				(width 0.1)
				(type default)
			)
			(layer "B.Fab")
		)
		(fp_line
			(start 0.12065 -0.305054)
			(end 0.12065 -0.2794)
			(stroke
				(width 0.1)
				(type default)
			)
			(layer "B.Fab")
		)
		(fp_line
			(start 0.67945 -0.305054)
			(end 0.12065 -0.305054)
			(stroke
				(width 0.1)
				(type default)
			)
			(layer "B.Fab")
		)
		(pad "1" smd circle
			(at 0.40005 0 90)
			(size 0 0)
			(layers "B.Cu" "B.Mask" "B.Paste")
			(net "SMB_HOST_3V3AUX_SCL")
		)
		(pad "2" smd circle
			(at -0.40005 0 90)
			(size 0 0)
			(layers "B.Cu" "B.Mask" "B.Paste")
			(net "P3V3_AUX")
		)
	)
	(footprint ""
		(layer "B.Cu")
		(at 371.273578 -189.56147 180)
		(property "Reference" "C559"
			(at 0 0 0)
			(layer "B.SilkS")
			(hide yes)
			(effects
				(font
					(size 1.27 1.27)
				)
				(justify mirror)
			)
		)
		(property "Value" ""
			(at 0 0 0)
			(layer "B.Fab")
			(effects
				(font
					(size 1.27 1.27)
				)
				(justify mirror)
			)
		)
		(duplicate_pad_numbers_are_jumpers no)
		(fp_line
			(start 0.7874 0.4064)
			(end 0.7874 -0.4064)
			(stroke
				(width 0.1524)
				(type default)
			)
			(layer "B.SilkS")
		)
		(fp_line
			(start 0.7874 -0.4064)
			(end -0.7874 -0.4064)
			(stroke
				(width 0.1524)
				(type default)
			)
			(layer "B.SilkS")
		)
		(fp_line
			(start -0.7874 0.4064)
			(end 0.7874 0.4064)
			(stroke
				(width 0.1524)
				(type default)
			)
			(layer "B.SilkS")
		)
		(fp_line
			(start -0.7874 -0.4064)
			(end -0.7874 0.4064)
			(stroke
				(width 0.1524)
				(type default)
			)
			(layer "B.SilkS")
		)
		(fp_line
			(start 0.67945 0.3048)
			(end 0.67945 -0.305054)
			(stroke
				(width 0.1)
				(type default)
			)
			(layer "B.Fab")
		)
		(fp_line
			(start 0.67945 -0.305054)
			(end 0.12065 -0.305054)
			(stroke
				(width 0.1)
				(type default)
			)
			(layer "B.Fab")
		)
		(fp_line
			(start 0.12065 0.3048)
			(end 0.67945 0.3048)
			(stroke
				(width 0.1)
				(type default)
			)
			(layer "B.Fab")
		)
		(fp_line
			(start 0.12065 0.2794)
			(end 0.12065 0.3048)
			(stroke
				(width 0.1)
				(type default)
			)
			(layer "B.Fab")
		)
		(fp_line
			(start 0.12065 -0.2794)
			(end -0.12065 -0.2794)
			(stroke
				(width 0.1)
				(type default)
			)
			(layer "B.Fab")
		)
		(fp_line
			(start 0.12065 -0.305054)
			(end 0.12065 -0.2794)
			(stroke
				(width 0.1)
				(type default)
			)
			(layer "B.Fab")
		)
		(fp_line
			(start -0.120396 0.3048)
			(end -0.120396 0.2794)
			(stroke
				(width 0.1)
				(type default)
			)
			(layer "B.Fab")
		)
		(fp_line
			(start -0.120396 0.2794)
			(end 0.12065 0.2794)
			(stroke
				(width 0.1)
				(type default)
			)
			(layer "B.Fab")
		)
		(fp_line
			(start -0.12065 -0.2794)
			(end -0.12065 -0.3048)
			(stroke
				(width 0.1)
				(type default)
			)
			(layer "B.Fab")
		)
		(fp_line
			(start -0.12065 -0.3048)
			(end -0.67945 -0.3048)
			(stroke
				(width 0.1)
				(type default)
			)
			(layer "B.Fab")
		)
		(fp_line
			(start -0.67945 0.3048)
			(end -0.120396 0.3048)
			(stroke
				(width 0.1)
				(type default)
			)
			(layer "B.Fab")
		)
		(fp_line
			(start -0.67945 -0.3048)
			(end -0.67945 0.3048)
			(stroke
				(width 0.1)
				(type default)
			)
			(layer "B.Fab")
		)
		(pad "1" smd circle
			(at 0.40005 0)
			(size 0 0)
			(layers "B.Cu" "B.Mask" "B.Paste")
			(net "PVNN_TERM_CPU0")
		)
		(pad "2" smd circle
			(at -0.40005 0)
			(size 0 0)
			(layers "B.Cu" "B.Mask" "B.Paste")
			(net "GND")
		)
	)
	(footprint ""
		(layer "B.Cu")
		(at 30.784546 -317.626746 180)
		(property "Reference" "R3896"
			(at 0 0 0)
			(layer "B.SilkS")
			(hide yes)
			(effects
				(font
					(size 1.27 1.27)
				)
				(justify mirror)
			)
		)
		(property "Value" ""
			(at 0 0 0)
			(layer "B.Fab")
			(effects
				(font
					(size 1.27 1.27)
				)
				(justify mirror)
			)
		)
		(duplicate_pad_numbers_are_jumpers no)
		(fp_line
			(start 0.7874 0.4064)
			(end 0.7874 -0.4064)
			(stroke
				(width 0.1524)
				(type default)
			)
			(layer "B.SilkS")
		)
		(fp_line
			(start 0.7874 -0.4064)
			(end -0.7874 -0.4064)
			(stroke
				(width 0.1524)
				(type default)
			)
			(layer "B.SilkS")
		)
		(fp_line
			(start -0.7874 0.4064)
			(end 0.7874 0.4064)
			(stroke
				(width 0.1524)
				(type default)
			)
			(layer "B.SilkS")
		)
		(fp_line
			(start -0.7874 -0.4064)
			(end -0.7874 0.4064)
			(stroke
				(width 0.1524)
				(type default)
			)
			(layer "B.SilkS")
		)
		(fp_line
			(start 0.67945 0.3048)
			(end 0.67945 -0.305054)
			(stroke
				(width 0.1)
				(type default)
			)
			(layer "B.Fab")
		)
		(fp_line
			(start 0.67945 -0.305054)
			(end 0.12065 -0.305054)
			(stroke
				(width 0.1)
				(type default)
			)
			(layer "B.Fab")
		)
		(fp_line
			(start 0.12065 0.3048)
			(end 0.67945 0.3048)
			(stroke
				(width 0.1)
				(type default)
			)
			(layer "B.Fab")
		)
		(fp_line
			(start 0.12065 0.2794)
			(end 0.12065 0.3048)
			(stroke
				(width 0.1)
				(type default)
			)
			(layer "B.Fab")
		)
		(fp_line
			(start 0.12065 -0.2794)
			(end -0.12065 -0.2794)
			(stroke
				(width 0.1)
				(type default)
			)
			(layer "B.Fab")
		)
		(fp_line
			(start 0.12065 -0.305054)
			(end 0.12065 -0.2794)
			(stroke
				(width 0.1)
				(type default)
			)
			(layer "B.Fab")
		)
		(fp_line
			(start -0.120396 0.3048)
			(end -0.120396 0.2794)
			(stroke
				(width 0.1)
				(type default)
			)
			(layer "B.Fab")
		)
		(fp_line
			(start -0.120396 0.2794)
			(end 0.12065 0.2794)
			(stroke
				(width 0.1)
				(type default)
			)
			(layer "B.Fab")
		)
		(fp_line
			(start -0.12065 -0.2794)
			(end -0.12065 -0.3048)
			(stroke
				(width 0.1)
				(type default)
			)
			(layer "B.Fab")
		)
		(fp_line
			(start -0.12065 -0.3048)
			(end -0.67945 -0.3048)
			(stroke
				(width 0.1)
				(type default)
			)
			(layer "B.Fab")
		)
		(fp_line
			(start -0.67945 0.3048)
			(end -0.120396 0.3048)
			(stroke
				(width 0.1)
				(type default)
			)
			(layer "B.Fab")
		)
		(fp_line
			(start -0.67945 -0.3048)
			(end -0.67945 0.3048)
			(stroke
				(width 0.1)
				(type default)
			)
			(layer "B.Fab")
		)
		(pad "1" smd circle
			(at 0.40005 0)
			(size 0 0)
			(layers "B.Cu" "B.Mask" "B.Paste")
			(net "I3C_SPD_DDRABCD_CPU1_LVC1_SCL_5")
		)
		(pad "2" smd circle
			(at -0.40005 0)
			(size 0 0)
			(layers "B.Cu" "B.Mask" "B.Paste")
			(net "I3C_SPD_DDRABCD_CPU1_LVC1_SCL")
		)
	)
	(footprint ""
		(layer "B.Cu")
		(at 355.397308 -252.176026 -90)
		(property "Reference" "C371"
			(at 0 0 90)
			(layer "B.SilkS")
			(hide yes)
			(effects
				(font
					(size 1.27 1.27)
				)
				(justify mirror)
			)
		)
		(property "Value" ""
			(at 0 0 90)
			(layer "B.Fab")
			(effects
				(font
					(size 1.27 1.27)
				)
				(justify mirror)
			)
		)
		(duplicate_pad_numbers_are_jumpers no)
		(fp_line
			(start -1.524 0.762)
			(end 1.524 0.762)
			(stroke
				(width 0.1524)
				(type default)
			)
			(layer "B.SilkS")
		)
		(fp_line
			(start 1.524 0.762)
			(end 1.524 -0.762)
			(stroke
				(width 0.1524)
				(type default)
			)
			(layer "B.SilkS")
		)
		(fp_line
			(start -1.524 -0.762)
			(end -1.524 0.762)
			(stroke
				(width 0.1524)
				(type default)
			)
			(layer "B.SilkS")
		)
		(fp_line
			(start 1.524 -0.762)
			(end -1.524 -0.762)
			(stroke
				(width 0.1524)
				(type default)
			)
			(layer "B.SilkS")
		)
		(fp_line
			(start -1.1049 0.724916)
			(end -1.1049 -0.724916)
			(stroke
				(width 0.1)
				(type default)
			)
			(layer "B.Fab")
		)
		(fp_line
			(start 1.1049 0.724916)
			(end -1.1049 0.724916)
			(stroke
				(width 0.1)
				(type default)
			)
			(layer "B.Fab")
		)
		(fp_line
			(start -1.1049 -0.724916)
			(end 1.1049 -0.724916)
			(stroke
				(width 0.1)
				(type default)
			)
			(layer "B.Fab")
		)
		(fp_line
			(start 1.1049 -0.724916)
			(end 1.1049 0.724916)
			(stroke
				(width 0.1)
				(type default)
			)
			(layer "B.Fab")
		)
		(pad "1" smd rect
			(at 0.889 0 270)
			(size 1.016 1.27)
			(layers "B.Cu" "B.Mask" "B.Paste")
			(net "PVCCIN_CPU0")
		)
		(pad "2" smd rect
			(at -0.889 0 270)
			(size 1.016 1.27)
			(layers "B.Cu" "B.Mask" "B.Paste")
			(net "GND")
		)
	)
)
